(kicad_pcb
	(version 20260206)
	(generator "pcbnew")
	(generator_version "10.0")
	(general
		(thickness 1.6)
		(legacy_teardrops no)
	)
	(paper "A4")
	(title_block
		(title "03242023_DA0F0TMBIJ0_F0T_Motherboard_J_brd_V01_OCP.brd")
		(comment 1 "Grand Teton / footprints 4391-4396 of 6105")
	)
	(layers
		(0 "F.Cu" signal "TOP")
		(4 "In1.Cu" signal "GND")
		(6 "In2.Cu" signal "IN1")
		(8 "In3.Cu" signal "GND1")
		(10 "In4.Cu" signal "IN2")
		(12 "In5.Cu" signal "GND2")
		(14 "In6.Cu" signal "IN3")
		(16 "In7.Cu" signal "GND3")
		(18 "In8.Cu" signal "VCC")
		(20 "In9.Cu" signal "VCC1")
		(22 "In10.Cu" signal "GND4")
		(24 "In11.Cu" signal "IN4")
		(26 "In12.Cu" signal "GND5")
		(28 "In13.Cu" signal "IN5")
		(30 "In14.Cu" signal "GND6")
		(32 "In15.Cu" signal "IN6")
		(34 "In16.Cu" signal "GND7")
		(2 "B.Cu" signal "BOTTOM")
		(9 "F.Adhes" user "F.Adhesive")
		(11 "B.Adhes" user "B.Adhesive")
		(13 "F.Paste" user "Package Geometry/Pastemask Top")
		(15 "B.Paste" user "Package Geometry/Pastemask Bottom")
		(5 "F.SilkS" user "Ref Des/Silkscreen Top")
		(7 "B.SilkS" user "Ref Des/Silkscreen Bottom")
		(1 "F.Mask" user "Board Geometry/Soldermask Top")
		(3 "B.Mask" user "Board Geometry/Soldermask Bottom")
		(17 "Dwgs.User" user "User.Drawings")
		(19 "Cmts.User" user "User.Comments")
		(21 "Eco1.User" user "User.Eco1")
		(23 "Eco2.User" user "User.Eco2")
		(25 "Edge.Cuts" user "Board Geometry/Outline")
		(27 "Margin" user)
		(31 "F.CrtYd" user "Package Geometry/Place Bound Top")
		(29 "B.CrtYd" user "Package Geometry/Place Bound Bottom")
		(35 "F.Fab" user "Ref Des/Assembly Top")
		(33 "B.Fab" user "Ref Des/Assembly Bottom")
	)
	(footprint ""
		(layer "B.Cu")
		(at 271.180814 -319.263776 180)
		(property "Reference" "C14"
			(at 0 0 0)
			(layer "B.SilkS")
			(hide yes)
			(effects
				(font
					(size 1.27 1.27)
				)
				(justify mirror)
			)
		)
		(property "Value" ""
			(at 0 0 0)
			(layer "B.Fab")
			(effects
				(font
					(size 1.27 1.27)
				)
				(justify mirror)
			)
		)
		(duplicate_pad_numbers_are_jumpers no)
		(fp_line
			(start 0.7874 0.4064)
			(end 0.7874 -0.4064)
			(stroke
				(width 0.1524)
				(type default)
			)
			(layer "B.SilkS")
		)
		(fp_line
			(start 0.7874 -0.4064)
			(end -0.7874 -0.4064)
			(stroke
				(width 0.1524)
				(type default)
			)
			(layer "B.SilkS")
		)
		(fp_line
			(start -0.7874 0.4064)
			(end 0.7874 0.4064)
			(stroke
				(width 0.1524)
				(type default)
			)
			(layer "B.SilkS")
		)
		(fp_line
			(start -0.7874 -0.4064)
			(end -0.7874 0.4064)
			(stroke
				(width 0.1524)
				(type default)
			)
			(layer "B.SilkS")
		)
		(fp_line
			(start 0.67945 0.3048)
			(end 0.67945 -0.305054)
			(stroke
				(width 0.1)
				(type default)
			)
			(layer "B.Fab")
		)
		(fp_line
			(start 0.67945 -0.305054)
			(end 0.12065 -0.305054)
			(stroke
				(width 0.1)
				(type default)
			)
			(layer "B.Fab")
		)
		(fp_line
			(start 0.12065 0.3048)
			(end 0.67945 0.3048)
			(stroke
				(width 0.1)
				(type default)
			)
			(layer "B.Fab")
		)
		(fp_line
			(start 0.12065 0.2794)
			(end 0.12065 0.3048)
			(stroke
				(width 0.1)
				(type default)
			)
			(layer "B.Fab")
		)
		(fp_line
			(start 0.12065 -0.2794)
			(end -0.12065 -0.2794)
			(stroke
				(width 0.1)
				(type default)
			)
			(layer "B.Fab")
		)
		(fp_line
			(start 0.12065 -0.305054)
			(end 0.12065 -0.2794)
			(stroke
				(width 0.1)
				(type default)
			)
			(layer "B.Fab")
		)
		(fp_line
			(start -0.120396 0.3048)
			(end -0.120396 0.2794)
			(stroke
				(width 0.1)
				(type default)
			)
			(layer "B.Fab")
		)
		(fp_line
			(start -0.120396 0.2794)
			(end 0.12065 0.2794)
			(stroke
				(width 0.1)
				(type default)
			)
			(layer "B.Fab")
		)
		(fp_line
			(start -0.12065 -0.2794)
			(end -0.12065 -0.3048)
			(stroke
				(width 0.1)
				(type default)
			)
			(layer "B.Fab")
		)
		(fp_line
			(start -0.12065 -0.3048)
			(end -0.67945 -0.3048)
			(stroke
				(width 0.1)
				(type default)
			)
			(layer "B.Fab")
		)
		(fp_line
			(start -0.67945 0.3048)
			(end -0.120396 0.3048)
			(stroke
				(width 0.1)
				(type default)
			)
			(layer "B.Fab")
		)
		(fp_line
			(start -0.67945 -0.3048)
			(end -0.67945 0.3048)
			(stroke
				(width 0.1)
				(type default)
			)
			(layer "B.Fab")
		)
		(pad "1" smd circle
			(at 0.40005 0)
			(size 0 0)
			(layers "B.Cu" "B.Mask" "B.Paste")
			(net "P3V3_AUX")
		)
		(pad "2" smd circle
			(at -0.40005 0)
			(size 0 0)
			(layers "B.Cu" "B.Mask" "B.Paste")
			(net "GND")
		)
	)
	(footprint ""
		(layer "B.Cu")
		(at 182.83428 -353.573842 90)
		(property "Reference" "PC1199_P1_3"
			(at 0 0 90)
			(layer "B.SilkS")
			(hide yes)
			(effects
				(font
					(size 1.27 1.27)
				)
				(justify mirror)
			)
		)
		(property "Value" ""
			(at 0 0 90)
			(layer "B.Fab")
			(effects
				(font
					(size 1.27 1.27)
				)
				(justify mirror)
			)
		)
		(duplicate_pad_numbers_are_jumpers no)
		(fp_line
			(start 1.524 -0.762)
			(end -1.524 -0.762)
			(stroke
				(width 0.1524)
				(type default)
			)
			(layer "B.SilkS")
		)
		(fp_line
			(start -1.524 -0.762)
			(end -1.524 0.762)
			(stroke
				(width 0.1524)
				(type default)
			)
			(layer "B.SilkS")
		)
		(fp_line
			(start 1.524 0.762)
			(end 1.524 -0.762)
			(stroke
				(width 0.1524)
				(type default)
			)
			(layer "B.SilkS")
		)
		(fp_line
			(start -1.524 0.762)
			(end 1.524 0.762)
			(stroke
				(width 0.1524)
				(type default)
			)
			(layer "B.SilkS")
		)
		(fp_line
			(start 1.1049 -0.724916)
			(end 1.1049 0.724916)
			(stroke
				(width 0.1)
				(type default)
			)
			(layer "B.Fab")
		)
		(fp_line
			(start -1.1049 -0.724916)
			(end 1.1049 -0.724916)
			(stroke
				(width 0.1)
				(type default)
			)
			(layer "B.Fab")
		)
		(fp_line
			(start 1.1049 0.724916)
			(end -1.1049 0.724916)
			(stroke
				(width 0.1)
				(type default)
			)
			(layer "B.Fab")
		)
		(fp_line
			(start -1.1049 0.724916)
			(end -1.1049 -0.724916)
			(stroke
				(width 0.1)
				(type default)
			)
			(layer "B.Fab")
		)
		(pad "1" smd rect
			(at 0.889 0 90)
			(size 1.016 1.27)
			(layers "B.Cu" "B.Mask" "B.Paste")
			(net "SW_P12V_PVCCFA_EHV_FIVRA_CPU1_R")
		)
		(pad "2" smd rect
			(at -0.889 0 90)
			(size 1.016 1.27)
			(layers "B.Cu" "B.Mask" "B.Paste")
			(net "GND")
		)
	)
	(footprint ""
		(layer "B.Cu")
		(at 27.0383 -129.380996 180)
		(property "Reference" "PR260"
			(at 0 0 0)
			(layer "B.SilkS")
			(hide yes)
			(effects
				(font
					(size 1.27 1.27)
				)
				(justify mirror)
			)
		)
		(property "Value" ""
			(at 0 0 0)
			(layer "B.Fab")
			(effects
				(font
					(size 1.27 1.27)
				)
				(justify mirror)
			)
		)
		(duplicate_pad_numbers_are_jumpers no)
		(fp_line
			(start 0.7874 0.4064)
			(end 0.7874 -0.4064)
			(stroke
				(width 0.1524)
				(type default)
			)
			(layer "B.SilkS")
		)
		(fp_line
			(start 0.7874 -0.4064)
			(end -0.7874 -0.4064)
			(stroke
				(width 0.1524)
				(type default)
			)
			(layer "B.SilkS")
		)
		(fp_line
			(start -0.7874 0.4064)
			(end 0.7874 0.4064)
			(stroke
				(width 0.1524)
				(type default)
			)
			(layer "B.SilkS")
		)
		(fp_line
			(start -0.7874 -0.4064)
			(end -0.7874 0.4064)
			(stroke
				(width 0.1524)
				(type default)
			)
			(layer "B.SilkS")
		)
		(fp_line
			(start 0.67945 0.3048)
			(end 0.67945 -0.305054)
			(stroke
				(width 0.1)
				(type default)
			)
			(layer "B.Fab")
		)
		(fp_line
			(start 0.67945 -0.305054)
			(end 0.12065 -0.305054)
			(stroke
				(width 0.1)
				(type default)
			)
			(layer "B.Fab")
		)
		(fp_line
			(start 0.12065 0.3048)
			(end 0.67945 0.3048)
			(stroke
				(width 0.1)
				(type default)
			)
			(layer "B.Fab")
		)
		(fp_line
			(start 0.12065 0.2794)
			(end 0.12065 0.3048)
			(stroke
				(width 0.1)
				(type default)
			)
			(layer "B.Fab")
		)
		(fp_line
			(start 0.12065 -0.2794)
			(end -0.12065 -0.2794)
			(stroke
				(width 0.1)
				(type default)
			)
			(layer "B.Fab")
		)
		(fp_line
			(start 0.12065 -0.305054)
			(end 0.12065 -0.2794)
			(stroke
				(width 0.1)
				(type default)
			)
			(layer "B.Fab")
		)
		(fp_line
			(start -0.120396 0.3048)
			(end -0.120396 0.2794)
			(stroke
				(width 0.1)
				(type default)
			)
			(layer "B.Fab")
		)
		(fp_line
			(start -0.120396 0.2794)
			(end 0.12065 0.2794)
			(stroke
				(width 0.1)
				(type default)
			)
			(layer "B.Fab")
		)
		(fp_line
			(start -0.12065 -0.2794)
			(end -0.12065 -0.3048)
			(stroke
				(width 0.1)
				(type default)
			)
			(layer "B.Fab")
		)
		(fp_line
			(start -0.12065 -0.3048)
			(end -0.67945 -0.3048)
			(stroke
				(width 0.1)
				(type default)
			)
			(layer "B.Fab")
		)
		(fp_line
			(start -0.67945 0.3048)
			(end -0.120396 0.3048)
			(stroke
				(width 0.1)
				(type default)
			)
			(layer "B.Fab")
		)
		(fp_line
			(start -0.67945 -0.3048)
			(end -0.67945 0.3048)
			(stroke
				(width 0.1)
				(type default)
			)
			(layer "B.Fab")
		)
		(pad "1" smd circle
			(at 0.40005 0)
			(size 0 0)
			(layers "B.Cu" "B.Mask" "B.Paste")
			(net "P12V_AUX")
		)
		(pad "2" smd circle
			(at -0.40005 0)
			(size 0 0)
			(layers "B.Cu" "B.Mask" "B.Paste")
			(net "PVCCINFAON_CPU1_CSPIN")
		)
	)
	(footprint ""
		(layer "B.Cu")
		(at 328.092816 -28.852876 -90)
		(property "Reference" "R609"
			(at 0 0 90)
			(layer "B.SilkS")
			(hide yes)
			(effects
				(font
					(size 1.27 1.27)
				)
				(justify mirror)
			)
		)
		(property "Value" ""
			(at 0 0 90)
			(layer "B.Fab")
			(effects
				(font
					(size 1.27 1.27)
				)
				(justify mirror)
			)
		)
		(duplicate_pad_numbers_are_jumpers no)
		(fp_line
			(start -0.7874 0.4064)
			(end 0.7874 0.4064)
			(stroke
				(width 0.1524)
				(type default)
			)
			(layer "B.SilkS")
		)
		(fp_line
			(start 0.7874 0.4064)
			(end 0.7874 -0.4064)
			(stroke
				(width 0.1524)
				(type default)
			)
			(layer "B.SilkS")
		)
		(fp_line
			(start -0.7874 -0.4064)
			(end -0.7874 0.4064)
			(stroke
				(width 0.1524)
				(type default)
			)
			(layer "B.SilkS")
		)
		(fp_line
			(start 0.7874 -0.4064)
			(end -0.7874 -0.4064)
			(stroke
				(width 0.1524)
				(type default)
			)
			(layer "B.SilkS")
		)
		(fp_line
			(start -0.67945 0.3048)
			(end -0.120396 0.3048)
			(stroke
				(width 0.1)
				(type default)
			)
			(layer "B.Fab")
		)
		(fp_line
			(start -0.120396 0.3048)
			(end -0.120396 0.2794)
			(stroke
				(width 0.1)
				(type default)
			)
			(layer "B.Fab")
		)
		(fp_line
			(start 0.12065 0.3048)
			(end 0.67945 0.3048)
			(stroke
				(width 0.1)
				(type default)
			)
			(layer "B.Fab")
		)
		(fp_line
			(start 0.67945 0.3048)
			(end 0.67945 -0.305054)
			(stroke
				(width 0.1)
				(type default)
			)
			(layer "B.Fab")
		)
		(fp_line
			(start -0.120396 0.2794)
			(end 0.12065 0.2794)
			(stroke
				(width 0.1)
				(type default)
			)
			(layer "B.Fab")
		)
		(fp_line
			(start 0.12065 0.2794)
			(end 0.12065 0.3048)
			(stroke
				(width 0.1)
				(type default)
			)
			(layer "B.Fab")
		)
		(fp_line
			(start -0.12065 -0.2794)
			(end -0.12065 -0.3048)
			(stroke
				(width 0.1)
				(type default)
			)
			(layer "B.Fab")
		)
		(fp_line
			(start 0.12065 -0.2794)
			(end -0.12065 -0.2794)
			(stroke
				(width 0.1)
				(type default)
			)
			(layer "B.Fab")
		)
		(fp_line
			(start -0.67945 -0.3048)
			(end -0.67945 0.3048)
			(stroke
				(width 0.1)
				(type default)
			)
			(layer "B.Fab")
		)
		(fp_line
			(start -0.12065 -0.3048)
			(end -0.67945 -0.3048)
			(stroke
				(width 0.1)
				(type default)
			)
			(layer "B.Fab")
		)
		(fp_line
			(start 0.12065 -0.305054)
			(end 0.12065 -0.2794)
			(stroke
				(width 0.1)
				(type default)
			)
			(layer "B.Fab")
		)
		(fp_line
			(start 0.67945 -0.305054)
			(end 0.12065 -0.305054)
			(stroke
				(width 0.1)
				(type default)
			)
			(layer "B.Fab")
		)
		(pad "1" smd circle
			(at 0.40005 0 90)
			(size 0 0)
			(layers "B.Cu" "B.Mask" "B.Paste")
			(net "P3V3_AUX")
		)
		(pad "2" smd circle
			(at -0.40005 0 90)
			(size 0 0)
			(layers "B.Cu" "B.Mask" "B.Paste")
			(net "FM_ESPI_CS_SWIZZLE")
		)
	)
	(footprint ""
		(layer "B.Cu")
		(at 179.887626 -415.633154 -90)
		(property "Reference" "R2807"
			(at 0 0 90)
			(layer "B.SilkS")
			(hide yes)
			(effects
				(font
					(size 1.27 1.27)
				)
				(justify mirror)
			)
		)
		(property "Value" ""
			(at 0 0 90)
			(layer "B.Fab")
			(effects
				(font
					(size 1.27 1.27)
				)
				(justify mirror)
			)
		)
		(duplicate_pad_numbers_are_jumpers no)
		(fp_line
			(start -0.7874 0.4064)
			(end 0.7874 0.4064)
			(stroke
				(width 0.1524)
				(type default)
			)
			(layer "B.SilkS")
		)
		(fp_line
			(start 0.7874 0.4064)
			(end 0.7874 -0.4064)
			(stroke
				(width 0.1524)
				(type default)
			)
			(layer "B.SilkS")
		)
		(fp_line
			(start -0.7874 -0.4064)
			(end -0.7874 0.4064)
			(stroke
				(width 0.1524)
				(type default)
			)
			(layer "B.SilkS")
		)
		(fp_line
			(start 0.7874 -0.4064)
			(end -0.7874 -0.4064)
			(stroke
				(width 0.1524)
				(type default)
			)
			(layer "B.SilkS")
		)
		(fp_line
			(start -0.67945 0.3048)
			(end -0.120396 0.3048)
			(stroke
				(width 0.1)
				(type default)
			)
			(layer "B.Fab")
		)
		(fp_line
			(start -0.120396 0.3048)
			(end -0.120396 0.2794)
			(stroke
				(width 0.1)
				(type default)
			)
			(layer "B.Fab")
		)
		(fp_line
			(start 0.12065 0.3048)
			(end 0.67945 0.3048)
			(stroke
				(width 0.1)
				(type default)
			)
			(layer "B.Fab")
		)
		(fp_line
			(start 0.67945 0.3048)
			(end 0.67945 -0.305054)
			(stroke
				(width 0.1)
				(type default)
			)
			(layer "B.Fab")
		)
		(fp_line
			(start -0.120396 0.2794)
			(end 0.12065 0.2794)
			(stroke
				(width 0.1)
				(type default)
			)
			(layer "B.Fab")
		)
		(fp_line
			(start 0.12065 0.2794)
			(end 0.12065 0.3048)
			(stroke
				(width 0.1)
				(type default)
			)
			(layer "B.Fab")
		)
		(fp_line
			(start -0.12065 -0.2794)
			(end -0.12065 -0.3048)
			(stroke
				(width 0.1)
				(type default)
			)
			(layer "B.Fab")
		)
		(fp_line
			(start 0.12065 -0.2794)
			(end -0.12065 -0.2794)
			(stroke
				(width 0.1)
				(type default)
			)
			(layer "B.Fab")
		)
		(fp_line
			(start -0.67945 -0.3048)
			(end -0.67945 0.3048)
			(stroke
				(width 0.1)
				(type default)
			)
			(layer "B.Fab")
		)
		(fp_line
			(start -0.12065 -0.3048)
			(end -0.67945 -0.3048)
			(stroke
				(width 0.1)
				(type default)
			)
			(layer "B.Fab")
		)
		(fp_line
			(start 0.12065 -0.305054)
			(end 0.12065 -0.2794)
			(stroke
				(width 0.1)
				(type default)
			)
			(layer "B.Fab")
		)
		(fp_line
			(start 0.67945 -0.305054)
			(end 0.12065 -0.305054)
			(stroke
				(width 0.1)
				(type default)
			)
			(layer "B.Fab")
		)
		(pad "1" smd circle
			(at 0.40005 0 90)
			(size 0 0)
			(layers "B.Cu" "B.Mask" "B.Paste")
			(net "P3V3_AUX")
		)
		(pad "2" smd circle
			(at -0.40005 0 90)
			(size 0 0)
			(layers "B.Cu" "B.Mask" "B.Paste")
			(net "SMB_FAN_3V3AUX_BUF_SDA")
		)
	)
	(footprint ""
		(layer "B.Cu")
		(at 294.91813 -403.031452 90)
		(property "Reference" "PR2517"
			(at 0 0 90)
			(layer "B.SilkS")
			(hide yes)
			(effects
				(font
					(size 1.27 1.27)
				)
				(justify mirror)
			)
		)
		(property "Value" ""
			(at 0 0 90)
			(layer "B.Fab")
			(effects
				(font
					(size 1.27 1.27)
				)
				(justify mirror)
			)
		)
		(duplicate_pad_numbers_are_jumpers no)
		(fp_line
			(start 0.7874 -0.4064)
			(end -0.7874 -0.4064)
			(stroke
				(width 0.1524)
				(type default)
			)
			(layer "B.SilkS")
		)
		(fp_line
			(start -0.7874 -0.4064)
			(end -0.7874 0.4064)
			(stroke
				(width 0.1524)
				(type default)
			)
			(layer "B.SilkS")
		)
		(fp_line
			(start 0.7874 0.4064)
			(end 0.7874 -0.4064)
			(stroke
				(width 0.1524)
				(type default)
			)
			(layer "B.SilkS")
		)
		(fp_line
			(start -0.7874 0.4064)
			(end 0.7874 0.4064)
			(stroke
				(width 0.1524)
				(type default)
			)
			(layer "B.SilkS")
		)
		(fp_line
			(start 0.67945 -0.305054)
			(end 0.12065 -0.305054)
			(stroke
				(width 0.1)
				(type default)
			)
			(layer "B.Fab")
		)
		(fp_line
			(start 0.12065 -0.305054)
			(end 0.12065 -0.2794)
			(stroke
				(width 0.1)
				(type default)
			)
			(layer "B.Fab")
		)
		(fp_line
			(start -0.12065 -0.3048)
			(end -0.67945 -0.3048)
			(stroke
				(width 0.1)
				(type default)
			)
			(layer "B.Fab")
		)
		(fp_line
			(start -0.67945 -0.3048)
			(end -0.67945 0.3048)
			(stroke
				(width 0.1)
				(type default)
			)
			(layer "B.Fab")
		)
		(fp_line
			(start 0.12065 -0.2794)
			(end -0.12065 -0.2794)
			(stroke
				(width 0.1)
				(type default)
			)
			(layer "B.Fab")
		)
		(fp_line
			(start -0.12065 -0.2794)
			(end -0.12065 -0.3048)
			(stroke
				(width 0.1)
				(type default)
			)
			(layer "B.Fab")
		)
		(fp_line
			(start 0.12065 0.2794)
			(end 0.12065 0.3048)
			(stroke
				(width 0.1)
				(type default)
			)
			(layer "B.Fab")
		)
		(fp_line
			(start -0.120396 0.2794)
			(end 0.12065 0.2794)
			(stroke
				(width 0.1)
				(type default)
			)
			(layer "B.Fab")
		)
		(fp_line
			(start 0.67945 0.3048)
			(end 0.67945 -0.305054)
			(stroke
				(width 0.1)
				(type default)
			)
			(layer "B.Fab")
		)
		(fp_line
			(start 0.12065 0.3048)
			(end 0.67945 0.3048)
			(stroke
				(width 0.1)
				(type default)
			)
			(layer "B.Fab")
		)
		(fp_line
			(start -0.120396 0.3048)
			(end -0.120396 0.2794)
			(stroke
				(width 0.1)
				(type default)
			)
			(layer "B.Fab")
		)
		(fp_line
			(start -0.67945 0.3048)
			(end -0.120396 0.3048)
			(stroke
				(width 0.1)
				(type default)
			)
			(layer "B.Fab")
		)
		(pad "1" smd circle
			(at 0.40005 0 270)
			(size 0 0)
			(layers "B.Cu" "B.Mask" "B.Paste")
			(net "P12V_HSC_ADC_N")
		)
		(pad "2" smd circle
			(at -0.40005 0 270)
			(size 0 0)
			(layers "B.Cu" "B.Mask" "B.Paste")
			(net "P12V_HSC_SENSE2_R3_N")
		)
	)
)
